FILE_TYPE=LIBRARY_PARTS;
primitive 'SW_PUSHBUTTON4P_12_G34_H2';
  pin
    '1':
      PIN_NUMBER='(1)';
      BIDIRECTIONAL='TRUE';
      INPUT_LOAD='(-0.01,0.01)';
      OUTPUT_LOAD='(1.0,-1.0)';
    '2':
      PIN_NUMBER='(2)';
      BIDIRECTIONAL='TRUE';
      INPUT_LOAD='(-0.01,0.01)';
      OUTPUT_LOAD='(1.0,-1.0)';
    '3':
      PIN_NUMBER='(3)';
      BIDIRECTIONAL='TRUE';
      INPUT_LOAD='(-0.01,0.01)';
      OUTPUT_LOAD='(1.0,-1.0)';
    '4':
      PIN_NUMBER='(4)';
      BIDIRECTIONAL='TRUE';
      INPUT_LOAD='(-0.01,0.01)';
      OUTPUT_LOAD='(1.0,-1.0)';
  end_pin;
  body
    PART_NAME='SW_PUSHBUTTON4P_12_G34_H2';
    BODY_NAME='SW_PUSHBUTTON4P_12_G34_H2';
    PHYS_DES_PREFIX='SW';
    CLASS='IO';
    NC_PINS='(H1,H2)';
  end_body;
end_primitive;

END.
